(kicad_pcb
	(version 20260206)
	(generator "pcbnew")
	(generator_version "10.0")
	(general
		(thickness 1.6)
		(legacy_teardrops no)
	)
	(paper "A4")
	(title_block
		(title "01162023_DA0F0TEBIF0_F0T_Expander_BD_F_brd_V02_OCP.brd")
		(comment 1 "Grand Teton / footprints 8999-9005 of 9728")
	)
	(layers
		(0 "F.Cu" signal "TOP")
		(4 "In1.Cu" signal "GND")
		(6 "In2.Cu" signal "VCC")
		(8 "In3.Cu" signal "VCC1")
		(10 "In4.Cu" signal "GND1")
		(12 "In5.Cu" signal "IN1")
		(14 "In6.Cu" signal "GND2")
		(16 "In7.Cu" signal "IN2")
		(18 "In8.Cu" signal "GND3")
		(20 "In9.Cu" signal "IN3")
		(22 "In10.Cu" signal "GND4")
		(24 "In11.Cu" signal "IN4")
		(26 "In12.Cu" signal "GND5")
		(28 "In13.Cu" signal "IN5")
		(30 "In14.Cu" signal "GND6")
		(32 "In15.Cu" signal "IN6")
		(34 "In16.Cu" signal "GND7")
		(2 "B.Cu" signal "BOTTOM")
		(9 "F.Adhes" user "F.Adhesive")
		(11 "B.Adhes" user "B.Adhesive")
		(13 "F.Paste" user "Package Geometry/Pastemask Top")
		(15 "B.Paste" user "Package Geometry/Pastemask Bottom")
		(5 "F.SilkS" user "Ref Des/Silkscreen Top")
		(7 "B.SilkS" user "Ref Des/Silkscreen Bottom")
		(1 "F.Mask" user "Board Geometry/Soldermask Top")
		(3 "B.Mask" user "Board Geometry/Soldermask Bottom")
		(17 "Dwgs.User" user "User.Drawings")
		(19 "Cmts.User" user "User.Comments")
		(21 "Eco1.User" user "User.Eco1")
		(23 "Eco2.User" user "User.Eco2")
		(25 "Edge.Cuts" user "Board Geometry/Outline")
		(27 "Margin" user)
		(31 "F.CrtYd" user "Package Geometry/Place Bound Top")
		(29 "B.CrtYd" user "Package Geometry/Place Bound Bottom")
		(35 "F.Fab" user "Ref Des/Assembly Top")
		(33 "B.Fab" user "Ref Des/Assembly Bottom")
	)
	(footprint ""
		(layer "B.Cu")
		(at 336.956654 -84.513928 -90)
		(property "Reference" "C2674"
			(at 0 0 90)
			(layer "B.SilkS")
			(hide yes)
			(effects
				(font
					(size 1.27 1.27)
				)
				(justify mirror)
			)
		)
		(property "Value" ""
			(at 0 0 90)
			(layer "B.Fab")
			(effects
				(font
					(size 1.27 1.27)
				)
				(justify mirror)
			)
		)
		(duplicate_pad_numbers_are_jumpers no)
		(fp_line
			(start -0.7874 0.4064)
			(end 0.7874 0.4064)
			(stroke
				(width 0.1524)
				(type default)
			)
			(layer "B.SilkS")
		)
		(fp_line
			(start 0.7874 0.4064)
			(end 0.7874 -0.4064)
			(stroke
				(width 0.1524)
				(type default)
			)
			(layer "B.SilkS")
		)
		(fp_line
			(start -0.7874 -0.4064)
			(end -0.7874 0.4064)
			(stroke
				(width 0.1524)
				(type default)
			)
			(layer "B.SilkS")
		)
		(fp_line
			(start 0.7874 -0.4064)
			(end -0.7874 -0.4064)
			(stroke
				(width 0.1524)
				(type default)
			)
			(layer "B.SilkS")
		)
		(fp_line
			(start -0.67945 0.3048)
			(end -0.120396 0.3048)
			(stroke
				(width 0.1)
				(type default)
			)
			(layer "B.Fab")
		)
		(fp_line
			(start -0.120396 0.3048)
			(end -0.120396 0.2794)
			(stroke
				(width 0.1)
				(type default)
			)
			(layer "B.Fab")
		)
		(fp_line
			(start 0.12065 0.3048)
			(end 0.67945 0.3048)
			(stroke
				(width 0.1)
				(type default)
			)
			(layer "B.Fab")
		)
		(fp_line
			(start 0.67945 0.3048)
			(end 0.67945 -0.305054)
			(stroke
				(width 0.1)
				(type default)
			)
			(layer "B.Fab")
		)
		(fp_line
			(start -0.120396 0.2794)
			(end 0.12065 0.2794)
			(stroke
				(width 0.1)
				(type default)
			)
			(layer "B.Fab")
		)
		(fp_line
			(start 0.12065 0.2794)
			(end 0.12065 0.3048)
			(stroke
				(width 0.1)
				(type default)
			)
			(layer "B.Fab")
		)
		(fp_line
			(start -0.12065 -0.2794)
			(end -0.12065 -0.3048)
			(stroke
				(width 0.1)
				(type default)
			)
			(layer "B.Fab")
		)
		(fp_line
			(start 0.12065 -0.2794)
			(end -0.12065 -0.2794)
			(stroke
				(width 0.1)
				(type default)
			)
			(layer "B.Fab")
		)
		(fp_line
			(start -0.67945 -0.3048)
			(end -0.67945 0.3048)
			(stroke
				(width 0.1)
				(type default)
			)
			(layer "B.Fab")
		)
		(fp_line
			(start -0.12065 -0.3048)
			(end -0.67945 -0.3048)
			(stroke
				(width 0.1)
				(type default)
			)
			(layer "B.Fab")
		)
		(fp_line
			(start 0.12065 -0.305054)
			(end 0.12065 -0.2794)
			(stroke
				(width 0.1)
				(type default)
			)
			(layer "B.Fab")
		)
		(fp_line
			(start 0.67945 -0.305054)
			(end 0.12065 -0.305054)
			(stroke
				(width 0.1)
				(type default)
			)
			(layer "B.Fab")
		)
		(pad "1" smd circle
			(at 0.40005 0 90)
			(size 0 0)
			(layers "B.Cu" "B.Mask" "B.Paste")
			(net "P3V3_VDD_9ZXL0851_8_15")
		)
		(pad "2" smd circle
			(at -0.40005 0 90)
			(size 0 0)
			(layers "B.Cu" "B.Mask" "B.Paste")
			(net "GND")
		)
	)
	(footprint ""
		(layer "B.Cu")
		(at 162.836098 -291.624766)
		(property "Reference" "C3234"
			(at 0 0 0)
			(layer "B.SilkS")
			(hide yes)
			(effects
				(font
					(size 1.27 1.27)
				)
				(justify mirror)
			)
		)
		(property "Value" ""
			(at 0 0 0)
			(layer "B.Fab")
			(effects
				(font
					(size 1.27 1.27)
				)
				(justify mirror)
			)
		)
		(duplicate_pad_numbers_are_jumpers no)
		(fp_line
			(start -0.299974 -0.150114)
			(end -0.299974 0.150114)
			(stroke
				(width 0.1)
				(type default)
			)
			(layer "B.Fab")
		)
		(fp_line
			(start -0.299974 0.150114)
			(end 0.299974 0.150114)
			(stroke
				(width 0.1)
				(type default)
			)
			(layer "B.Fab")
		)
		(fp_line
			(start 0.299974 -0.150114)
			(end -0.299974 -0.150114)
			(stroke
				(width 0.1)
				(type default)
			)
			(layer "B.Fab")
		)
		(fp_line
			(start 0.299974 0.150114)
			(end 0.299974 -0.150114)
			(stroke
				(width 0.1)
				(type default)
			)
			(layer "B.Fab")
		)
		(pad "1" smd rect
			(at 0.2667 0 180)
			(size 0.3048 0.381)
			(layers "B.Cu" "B.Mask" "B.Paste")
			(net "PCEPLL7_VDDA18_PEX1")
		)
		(pad "2" smd rect
			(at -0.2667 0 180)
			(size 0.3048 0.381)
			(layers "B.Cu" "B.Mask" "B.Paste")
			(net "GND")
		)
	)
	(footprint ""
		(layer "B.Cu")
		(at 227.118418 -150.425912 90)
		(property "Reference" "C2801"
			(at 0 0 90)
			(layer "B.SilkS")
			(hide yes)
			(effects
				(font
					(size 1.27 1.27)
				)
				(justify mirror)
			)
		)
		(property "Value" ""
			(at 0 0 90)
			(layer "B.Fab")
			(effects
				(font
					(size 1.27 1.27)
				)
				(justify mirror)
			)
		)
		(duplicate_pad_numbers_are_jumpers no)
		(fp_line
			(start 0.7874 -0.4064)
			(end -0.7874 -0.4064)
			(stroke
				(width 0.1524)
				(type default)
			)
			(layer "B.SilkS")
		)
		(fp_line
			(start -0.7874 -0.4064)
			(end -0.7874 0.4064)
			(stroke
				(width 0.1524)
				(type default)
			)
			(layer "B.SilkS")
		)
		(fp_line
			(start 0.7874 0.4064)
			(end 0.7874 -0.4064)
			(stroke
				(width 0.1524)
				(type default)
			)
			(layer "B.SilkS")
		)
		(fp_line
			(start -0.7874 0.4064)
			(end 0.7874 0.4064)
			(stroke
				(width 0.1524)
				(type default)
			)
			(layer "B.SilkS")
		)
		(fp_line
			(start 0.67945 -0.305054)
			(end 0.12065 -0.305054)
			(stroke
				(width 0.1)
				(type default)
			)
			(layer "B.Fab")
		)
		(fp_line
			(start 0.12065 -0.305054)
			(end 0.12065 -0.2794)
			(stroke
				(width 0.1)
				(type default)
			)
			(layer "B.Fab")
		)
		(fp_line
			(start -0.12065 -0.3048)
			(end -0.67945 -0.3048)
			(stroke
				(width 0.1)
				(type default)
			)
			(layer "B.Fab")
		)
		(fp_line
			(start -0.67945 -0.3048)
			(end -0.67945 0.3048)
			(stroke
				(width 0.1)
				(type default)
			)
			(layer "B.Fab")
		)
		(fp_line
			(start 0.12065 -0.2794)
			(end -0.12065 -0.2794)
			(stroke
				(width 0.1)
				(type default)
			)
			(layer "B.Fab")
		)
		(fp_line
			(start -0.12065 -0.2794)
			(end -0.12065 -0.3048)
			(stroke
				(width 0.1)
				(type default)
			)
			(layer "B.Fab")
		)
		(fp_line
			(start 0.12065 0.2794)
			(end 0.12065 0.3048)
			(stroke
				(width 0.1)
				(type default)
			)
			(layer "B.Fab")
		)
		(fp_line
			(start -0.120396 0.2794)
			(end 0.12065 0.2794)
			(stroke
				(width 0.1)
				(type default)
			)
			(layer "B.Fab")
		)
		(fp_line
			(start 0.67945 0.3048)
			(end 0.67945 -0.305054)
			(stroke
				(width 0.1)
				(type default)
			)
			(layer "B.Fab")
		)
		(fp_line
			(start 0.12065 0.3048)
			(end 0.67945 0.3048)
			(stroke
				(width 0.1)
				(type default)
			)
			(layer "B.Fab")
		)
		(fp_line
			(start -0.120396 0.3048)
			(end -0.120396 0.2794)
			(stroke
				(width 0.1)
				(type default)
			)
			(layer "B.Fab")
		)
		(fp_line
			(start -0.67945 0.3048)
			(end -0.120396 0.3048)
			(stroke
				(width 0.1)
				(type default)
			)
			(layer "B.Fab")
		)
		(pad "1" smd circle
			(at 0.40005 0 270)
			(size 0 0)
			(layers "B.Cu" "B.Mask" "B.Paste")
			(net "P3V3_CLK_GEN_VDDMXCK_CK440_PEX")
		)
		(pad "2" smd circle
			(at -0.40005 0 270)
			(size 0 0)
			(layers "B.Cu" "B.Mask" "B.Paste")
			(net "GND")
		)
	)
	(footprint ""
		(layer "B.Cu")
		(at 124.236734 -321.387978 -90)
		(property "Reference" "R6478"
			(at 0 0 90)
			(layer "B.SilkS")
			(hide yes)
			(effects
				(font
					(size 1.27 1.27)
				)
				(justify mirror)
			)
		)
		(property "Value" ""
			(at 0 0 90)
			(layer "B.Fab")
			(effects
				(font
					(size 1.27 1.27)
				)
				(justify mirror)
			)
		)
		(duplicate_pad_numbers_are_jumpers no)
		(fp_line
			(start -0.7874 0.4064)
			(end 0.7874 0.4064)
			(stroke
				(width 0.1524)
				(type default)
			)
			(layer "B.SilkS")
		)
		(fp_line
			(start 0.7874 0.4064)
			(end 0.7874 -0.4064)
			(stroke
				(width 0.1524)
				(type default)
			)
			(layer "B.SilkS")
		)
		(fp_line
			(start -0.7874 -0.4064)
			(end -0.7874 0.4064)
			(stroke
				(width 0.1524)
				(type default)
			)
			(layer "B.SilkS")
		)
		(fp_line
			(start 0.7874 -0.4064)
			(end -0.7874 -0.4064)
			(stroke
				(width 0.1524)
				(type default)
			)
			(layer "B.SilkS")
		)
		(fp_line
			(start -0.67945 0.3048)
			(end -0.120396 0.3048)
			(stroke
				(width 0.1)
				(type default)
			)
			(layer "B.Fab")
		)
		(fp_line
			(start -0.120396 0.3048)
			(end -0.120396 0.2794)
			(stroke
				(width 0.1)
				(type default)
			)
			(layer "B.Fab")
		)
		(fp_line
			(start 0.12065 0.3048)
			(end 0.67945 0.3048)
			(stroke
				(width 0.1)
				(type default)
			)
			(layer "B.Fab")
		)
		(fp_line
			(start 0.67945 0.3048)
			(end 0.67945 -0.305054)
			(stroke
				(width 0.1)
				(type default)
			)
			(layer "B.Fab")
		)
		(fp_line
			(start -0.120396 0.2794)
			(end 0.12065 0.2794)
			(stroke
				(width 0.1)
				(type default)
			)
			(layer "B.Fab")
		)
		(fp_line
			(start 0.12065 0.2794)
			(end 0.12065 0.3048)
			(stroke
				(width 0.1)
				(type default)
			)
			(layer "B.Fab")
		)
		(fp_line
			(start -0.12065 -0.2794)
			(end -0.12065 -0.3048)
			(stroke
				(width 0.1)
				(type default)
			)
			(layer "B.Fab")
		)
		(fp_line
			(start 0.12065 -0.2794)
			(end -0.12065 -0.2794)
			(stroke
				(width 0.1)
				(type default)
			)
			(layer "B.Fab")
		)
		(fp_line
			(start -0.67945 -0.3048)
			(end -0.67945 0.3048)
			(stroke
				(width 0.1)
				(type default)
			)
			(layer "B.Fab")
		)
		(fp_line
			(start -0.12065 -0.3048)
			(end -0.67945 -0.3048)
			(stroke
				(width 0.1)
				(type default)
			)
			(layer "B.Fab")
		)
		(fp_line
			(start 0.12065 -0.305054)
			(end 0.12065 -0.2794)
			(stroke
				(width 0.1)
				(type default)
			)
			(layer "B.Fab")
		)
		(fp_line
			(start 0.67945 -0.305054)
			(end 0.12065 -0.305054)
			(stroke
				(width 0.1)
				(type default)
			)
			(layer "B.Fab")
		)
		(pad "1" smd circle
			(at 0.40005 0 90)
			(size 0 0)
			(layers "B.Cu" "B.Mask" "B.Paste")
			(net "P0V8_SERDES_VDDA_PEX1")
		)
		(pad "2" smd circle
			(at -0.40005 0 90)
			(size 0 0)
			(layers "B.Cu" "B.Mask" "B.Paste")
			(net "P0V8_SERDES_VDDA_PEX1_C3")
		)
	)
	(footprint ""
		(layer "B.Cu")
		(at 420.05504 -97.663 180)
		(property "Reference" "R379"
			(at 0 0 0)
			(layer "B.SilkS")
			(hide yes)
			(effects
				(font
					(size 1.27 1.27)
				)
				(justify mirror)
			)
		)
		(property "Value" ""
			(at 0 0 0)
			(layer "B.Fab")
			(effects
				(font
					(size 1.27 1.27)
				)
				(justify mirror)
			)
		)
		(duplicate_pad_numbers_are_jumpers no)
		(fp_line
			(start 0.7874 0.4064)
			(end 0.7874 -0.4064)
			(stroke
				(width 0.1524)
				(type default)
			)
			(layer "B.SilkS")
		)
		(fp_line
			(start 0.7874 -0.4064)
			(end -0.7874 -0.4064)
			(stroke
				(width 0.1524)
				(type default)
			)
			(layer "B.SilkS")
		)
		(fp_line
			(start -0.7874 0.4064)
			(end 0.7874 0.4064)
			(stroke
				(width 0.1524)
				(type default)
			)
			(layer "B.SilkS")
		)
		(fp_line
			(start -0.7874 -0.4064)
			(end -0.7874 0.4064)
			(stroke
				(width 0.1524)
				(type default)
			)
			(layer "B.SilkS")
		)
		(fp_line
			(start 0.67945 0.3048)
			(end 0.67945 -0.305054)
			(stroke
				(width 0.1)
				(type default)
			)
			(layer "B.Fab")
		)
		(fp_line
			(start 0.67945 -0.305054)
			(end 0.12065 -0.305054)
			(stroke
				(width 0.1)
				(type default)
			)
			(layer "B.Fab")
		)
		(fp_line
			(start 0.12065 0.3048)
			(end 0.67945 0.3048)
			(stroke
				(width 0.1)
				(type default)
			)
			(layer "B.Fab")
		)
		(fp_line
			(start 0.12065 0.2794)
			(end 0.12065 0.3048)
			(stroke
				(width 0.1)
				(type default)
			)
			(layer "B.Fab")
		)
		(fp_line
			(start 0.12065 -0.2794)
			(end -0.12065 -0.2794)
			(stroke
				(width 0.1)
				(type default)
			)
			(layer "B.Fab")
		)
		(fp_line
			(start 0.12065 -0.305054)
			(end 0.12065 -0.2794)
			(stroke
				(width 0.1)
				(type default)
			)
			(layer "B.Fab")
		)
		(fp_line
			(start -0.120396 0.3048)
			(end -0.120396 0.2794)
			(stroke
				(width 0.1)
				(type default)
			)
			(layer "B.Fab")
		)
		(fp_line
			(start -0.120396 0.2794)
			(end 0.12065 0.2794)
			(stroke
				(width 0.1)
				(type default)
			)
			(layer "B.Fab")
		)
		(fp_line
			(start -0.12065 -0.2794)
			(end -0.12065 -0.3048)
			(stroke
				(width 0.1)
				(type default)
			)
			(layer "B.Fab")
		)
		(fp_line
			(start -0.12065 -0.3048)
			(end -0.67945 -0.3048)
			(stroke
				(width 0.1)
				(type default)
			)
			(layer "B.Fab")
		)
		(fp_line
			(start -0.67945 0.3048)
			(end -0.120396 0.3048)
			(stroke
				(width 0.1)
				(type default)
			)
			(layer "B.Fab")
		)
		(fp_line
			(start -0.67945 -0.3048)
			(end -0.67945 0.3048)
			(stroke
				(width 0.1)
				(type default)
			)
			(layer "B.Fab")
		)
		(pad "1" smd circle
			(at 0.40005 0)
			(size 0 0)
			(layers "B.Cu" "B.Mask" "B.Paste")
			(net "PWRGD_NIC7_PWR_GOOD")
		)
		(pad "2" smd circle
			(at -0.40005 0)
			(size 0 0)
			(layers "B.Cu" "B.Mask" "B.Paste")
			(net "GND")
		)
	)
	(footprint ""
		(layer "B.Cu")
		(at 60.124848 -297.79976 90)
		(property "Reference" "C1114"
			(at 0 0 90)
			(layer "B.SilkS")
			(hide yes)
			(effects
				(font
					(size 1.27 1.27)
				)
				(justify mirror)
			)
		)
		(property "Value" ""
			(at 0 0 90)
			(layer "B.Fab")
			(effects
				(font
					(size 1.27 1.27)
				)
				(justify mirror)
			)
		)
		(duplicate_pad_numbers_are_jumpers no)
		(fp_line
			(start 0.299974 -0.150114)
			(end -0.299974 -0.150114)
			(stroke
				(width 0.1)
				(type default)
			)
			(layer "B.Fab")
		)
		(fp_line
			(start -0.299974 -0.150114)
			(end -0.299974 0.150114)
			(stroke
				(width 0.1)
				(type default)
			)
			(layer "B.Fab")
		)
		(fp_line
			(start 0.299974 0.150114)
			(end 0.299974 -0.150114)
			(stroke
				(width 0.1)
				(type default)
			)
			(layer "B.Fab")
		)
		(fp_line
			(start -0.299974 0.150114)
			(end 0.299974 0.150114)
			(stroke
				(width 0.1)
				(type default)
			)
			(layer "B.Fab")
		)
		(pad "1" smd rect
			(at 0.2667 0 270)
			(size 0.3048 0.381)
			(layers "B.Cu" "B.Mask" "B.Paste")
			(net "P0V8_PEX0")
		)
		(pad "2" smd rect
			(at -0.2667 0 270)
			(size 0.3048 0.381)
			(layers "B.Cu" "B.Mask" "B.Paste")
			(net "GND")
		)
	)
	(footprint ""
		(layer "B.Cu")
		(at 379.766322 -248.203974 180)
		(property "Reference" "R964"
			(at 0 0 0)
			(layer "B.SilkS")
			(hide yes)
			(effects
				(font
					(size 1.27 1.27)
				)
				(justify mirror)
			)
		)
		(property "Value" ""
			(at 0 0 0)
			(layer "B.Fab")
			(effects
				(font
					(size 1.27 1.27)
				)
				(justify mirror)
			)
		)
		(duplicate_pad_numbers_are_jumpers no)
		(fp_line
			(start 0.7874 0.4064)
			(end 0.7874 -0.4064)
			(stroke
				(width 0.1524)
				(type default)
			)
			(layer "B.SilkS")
		)
		(fp_line
			(start 0.7874 -0.4064)
			(end -0.7874 -0.4064)
			(stroke
				(width 0.1524)
				(type default)
			)
			(layer "B.SilkS")
		)
		(fp_line
			(start -0.7874 0.4064)
			(end 0.7874 0.4064)
			(stroke
				(width 0.1524)
				(type default)
			)
			(layer "B.SilkS")
		)
		(fp_line
			(start -0.7874 -0.4064)
			(end -0.7874 0.4064)
			(stroke
				(width 0.1524)
				(type default)
			)
			(layer "B.SilkS")
		)
		(fp_line
			(start 0.67945 0.3048)
			(end 0.67945 -0.305054)
			(stroke
				(width 0.1)
				(type default)
			)
			(layer "B.Fab")
		)
		(fp_line
			(start 0.67945 -0.305054)
			(end 0.12065 -0.305054)
			(stroke
				(width 0.1)
				(type default)
			)
			(layer "B.Fab")
		)
		(fp_line
			(start 0.12065 0.3048)
			(end 0.67945 0.3048)
			(stroke
				(width 0.1)
				(type default)
			)
			(layer "B.Fab")
		)
		(fp_line
			(start 0.12065 0.2794)
			(end 0.12065 0.3048)
			(stroke
				(width 0.1)
				(type default)
			)
			(layer "B.Fab")
		)
		(fp_line
			(start 0.12065 -0.2794)
			(end -0.12065 -0.2794)
			(stroke
				(width 0.1)
				(type default)
			)
			(layer "B.Fab")
		)
		(fp_line
			(start 0.12065 -0.305054)
			(end 0.12065 -0.2794)
			(stroke
				(width 0.1)
				(type default)
			)
			(layer "B.Fab")
		)
		(fp_line
			(start -0.120396 0.3048)
			(end -0.120396 0.2794)
			(stroke
				(width 0.1)
				(type default)
			)
			(layer "B.Fab")
		)
		(fp_line
			(start -0.120396 0.2794)
			(end 0.12065 0.2794)
			(stroke
				(width 0.1)
				(type default)
			)
			(layer "B.Fab")
		)
		(fp_line
			(start -0.12065 -0.2794)
			(end -0.12065 -0.3048)
			(stroke
				(width 0.1)
				(type default)
			)
			(layer "B.Fab")
		)
		(fp_line
			(start -0.12065 -0.3048)
			(end -0.67945 -0.3048)
			(stroke
				(width 0.1)
				(type default)
			)
			(layer "B.Fab")
		)
		(fp_line
			(start -0.67945 0.3048)
			(end -0.120396 0.3048)
			(stroke
				(width 0.1)
				(type default)
			)
			(layer "B.Fab")
		)
		(fp_line
			(start -0.67945 -0.3048)
			(end -0.67945 0.3048)
			(stroke
				(width 0.1)
				(type default)
			)
			(layer "B.Fab")
		)
		(pad "1" smd circle
			(at 0.40005 0)
			(size 0 0)
			(layers "B.Cu" "B.Mask" "B.Paste")
			(net "UART_PEX3_SDB_BUF_TX")
		)
		(pad "2" smd circle
			(at -0.40005 0)
			(size 0 0)
			(layers "B.Cu" "B.Mask" "B.Paste")
			(net "P3V3_AUX")
		)
	)
)
